# BASEBOARD_FAB2 (Tioga Pass) — schematic netlist excerpt (pin names and nets, part order shuffled) for the footprints in the layout excerpt that follows; sources: Cadence DE-HDL packaged netlist, KiCad conversion of Wiwynn_Tioga_Pass_MB.brd

R1U11  RES  0.0 5% CHIP  pkg 0402  page 159 : A = SMB_VR_STBY_LVC3_SCL_R ; B = SMB_VR_STBY_LVC3_SCL
C1B15  CAP_A  0.01UF 25V 10% X7R  pkg 0402V  page 161 : A = FAN_TACH2 ; B = GND
C8F11  CAP_A  0.01UF 25V 10% X7R  pkg 0402V  page 185 : A = SATA6G_S0_TX_DN ; B = P3E_PCH_M2_SATA6G_TX_R_DN

(kicad_pcb
	(version 20260206)
	(generator "pcbnew")
	(generator_version "10.0")
	(general
		(thickness 1.6)
		(legacy_teardrops no)
	)
	(paper "A4")
	(title_block
		(title "Wiwynn_Tioga_Pass_MB.brd")
		(comment 1 "Tioga Pass / footprints 1358-1360 of 4770")
	)
	(layers
		(0 "F.Cu" signal "TOP")
		(4 "In1.Cu" signal "L2GND")
		(6 "In2.Cu" signal "L3")
		(8 "In3.Cu" signal "L4GND")
		(10 "In4.Cu" signal "L5")
		(12 "In5.Cu" signal "L6GND")
		(14 "In6.Cu" signal "L7VCC")
		(16 "In7.Cu" signal "L8VCC")
		(18 "In8.Cu" signal "L9GND")
		(20 "In9.Cu" signal "L10")
		(22 "In10.Cu" signal "L11GND")
		(24 "In11.Cu" signal "L12")
		(26 "In12.Cu" signal "L13GND")
		(2 "B.Cu" signal "BOTTOM")
		(9 "F.Adhes" user "F.Adhesive")
		(11 "B.Adhes" user "B.Adhesive")
		(13 "F.Paste" user "Package Geometry/Pastemask Top")
		(15 "B.Paste" user "Package Geometry/Pastemask Bottom")
		(5 "F.SilkS" user "Ref Des/Silkscreen Top")
		(7 "B.SilkS" user "Ref Des/Silkscreen Bottom")
		(1 "F.Mask" user "Board Geometry/Soldermask Top")
		(3 "B.Mask" user "Board Geometry/Soldermask Bottom")
		(17 "Dwgs.User" user "User.Drawings")
		(19 "Cmts.User" user "User.Comments")
		(21 "Eco1.User" user "User.Eco1")
		(23 "Eco2.User" user "User.Eco2")
		(25 "Edge.Cuts" user "Board Geometry/Outline")
		(27 "Margin" user)
		(31 "F.CrtYd" user "Package Geometry/Place Bound Top")
		(29 "B.CrtYd" user "Package Geometry/Place Bound Bottom")
		(35 "F.Fab" user "Ref Des/Assembly Top")
		(33 "B.Fab" user "Ref Des/Assembly Bottom")
	)
	(footprint ""
		(layer "F.Cu")
		(at 378.254768 -32.3215 90)
		(property "Reference" "C8F11"
			(at -0.8382 -0.67818 90)
			(unlocked yes)
			(layer "F.SilkS")
			(effects
				(font
					(size 0.4064 0.254)
					(thickness 0.1524)
				)
				(justify left)
			)
		)
		(property "Value" ""
			(at 0 0 90)
			(layer "F.Fab")
			(effects
				(font
					(size 1.27 1.27)
				)
			)
		)
		(duplicate_pad_numbers_are_jumpers no)
		(fp_poly
			(pts
				(xy 0.3048 -0.1016) (xy 0.3048 0.9906) (xy -0.3048 0.9906) (xy -0.3048 -0.1016)
			)
			(stroke
				(width 0)
				(type default)
			)
			(fill no)
			(layer "F.CrtYd")
		)
		(fp_line
			(start 0.3048 -0.1016)
			(end -0.3048 -0.1016)
			(stroke
				(width 0.1)
				(type default)
			)
			(layer "F.Fab")
		)
		(fp_line
			(start -0.3048 -0.1016)
			(end -0.3048 0.9906)
			(stroke
				(width 0.1)
				(type default)
			)
			(layer "F.Fab")
		)
		(fp_line
			(start 0.3048 0.9906)
			(end 0.3048 -0.1016)
			(stroke
				(width 0.1)
				(type default)
			)
			(layer "F.Fab")
		)
		(fp_line
			(start -0.3048 0.9906)
			(end 0.3048 0.9906)
			(stroke
				(width 0.1)
				(type default)
			)
			(layer "F.Fab")
		)
		(pad "1" smd rect
			(at 0 0 90)
			(size 0.508 0.508)
			(layers "F.Cu" "F.Mask" "F.Paste")
			(net "SATA6G_S0_TX_DN")
		)
		(pad "2" smd rect
			(at 0 0.889 90)
			(size 0.508 0.508)
			(layers "F.Cu" "F.Mask" "F.Paste")
			(net "P3E_PCH_M2_SATA6G_TX_R_DN")
		)
		(zone
			(layer "F.Cu")
			(hatch none 0.5)
			(connect_pads
				(clearance 0)
			)
			(min_thickness 0.25)
			(keepout
				(tracks allowed)
				(vias not_allowed)
				(pads allowed)
				(copperpour not_allowed)
				(footprints allowed)
			)
			(placement
				(enabled no)
				(sheetname "")
			)
			(fill
				(thermal_gap 0.5)
				(thermal_bridge_width 0.5)
				(island_removal_mode 0)
			)
			(polygon
				(pts
					(xy 378.508768 -32.0675) (xy 378.508768 -32.5755) (xy 378.889768 -32.5755) (xy 378.889768 -32.0675)
				)
			)
		)
		(zone
			(layer "F.Cu")
			(hatch none 0.5)
			(connect_pads
				(clearance 0)
			)
			(min_thickness 0.25)
			(keepout
				(tracks not_allowed)
				(vias allowed)
				(pads allowed)
				(copperpour not_allowed)
				(footprints allowed)
			)
			(placement
				(enabled no)
				(sheetname "")
			)
			(fill
				(thermal_gap 0.5)
				(thermal_bridge_width 0.5)
				(island_removal_mode 0)
			)
			(polygon
				(pts
					(xy 378.889768 -32.0675) (xy 378.889768 -32.5755) (xy 378.508768 -32.5755) (xy 378.508768 -32.0675)
				)
			)
		)
	)
	(footprint ""
		(layer "F.Cu")
		(at 17.91335 -118.145052 180)
		(property "Reference" "C1B15"
			(at 0 0 180)
			(layer "F.SilkS")
			(hide yes)
			(effects
				(font
					(size 1.27 1.27)
				)
			)
		)
		(property "Value" ""
			(at 0 0 180)
			(layer "F.Fab")
			(effects
				(font
					(size 1.27 1.27)
				)
			)
		)
		(duplicate_pad_numbers_are_jumpers no)
		(fp_rect
			(start 0.3048 -0.1016)
			(end -0.3048 0.9906)
			(stroke
				(width 0)
				(type default)
			)
			(fill no)
			(layer "F.CrtYd")
		)
		(fp_line
			(start 0.3048 0.9906)
			(end 0.3048 -0.1016)
			(stroke
				(width 0.1)
				(type default)
			)
			(layer "F.Fab")
		)
		(fp_line
			(start 0.3048 -0.1016)
			(end -0.3048 -0.1016)
			(stroke
				(width 0.1)
				(type default)
			)
			(layer "F.Fab")
		)
		(fp_line
			(start -0.3048 0.9906)
			(end 0.3048 0.9906)
			(stroke
				(width 0.1)
				(type default)
			)
			(layer "F.Fab")
		)
		(fp_line
			(start -0.3048 -0.1016)
			(end -0.3048 0.9906)
			(stroke
				(width 0.1)
				(type default)
			)
			(layer "F.Fab")
		)
		(pad "1" smd rect
			(at 0 0 180)
			(size 0.508 0.508)
			(layers "F.Cu" "F.Mask" "F.Paste")
			(net "FAN_TACH2")
		)
		(pad "2" smd rect
			(at 0 0.889 180)
			(size 0.508 0.508)
			(layers "F.Cu" "F.Mask" "F.Paste")
			(net "GND")
		)
		(zone
			(layer "F.Cu")
			(hatch none 0.5)
			(connect_pads
				(clearance 0)
			)
			(min_thickness 0.25)
			(keepout
				(tracks allowed)
				(vias not_allowed)
				(pads allowed)
				(copperpour not_allowed)
				(footprints allowed)
			)
			(placement
				(enabled no)
				(sheetname "")
			)
			(fill
				(thermal_gap 0.5)
				(thermal_bridge_width 0.5)
				(island_removal_mode 0)
			)
			(polygon
				(pts
					(xy 17.65935 -118.399052) (xy 18.16735 -118.399052) (xy 18.16735 -118.780052) (xy 17.65935 -118.780052)
				)
			)
		)
		(zone
			(layer "F.Cu")
			(hatch none 0.5)
			(connect_pads
				(clearance 0)
			)
			(min_thickness 0.25)
			(keepout
				(tracks not_allowed)
				(vias allowed)
				(pads allowed)
				(copperpour not_allowed)
				(footprints allowed)
			)
			(placement
				(enabled no)
				(sheetname "")
			)
			(fill
				(thermal_gap 0.5)
				(thermal_bridge_width 0.5)
				(island_removal_mode 0)
			)
			(polygon
				(pts
					(xy 17.65935 -118.399052) (xy 18.16735 -118.399052) (xy 18.16735 -118.780052) (xy 17.65935 -118.780052)
				)
			)
		)
	)
	(footprint ""
		(layer "F.Cu")
		(at 417.5506 -18.7452)
		(property "Reference" "R1U11"
			(at 0 0 0)
			(layer "F.SilkS")
			(hide yes)
			(effects
				(font
					(size 1.27 1.27)
				)
			)
		)
		(property "Value" ""
			(at 0 0 0)
			(layer "F.Fab")
			(effects
				(font
					(size 1.27 1.27)
				)
			)
		)
		(duplicate_pad_numbers_are_jumpers no)
		(fp_poly
			(pts
				(xy -0.2794 -0.1016) (xy 0.2794 -0.1016) (xy 0.2794 0.9906) (xy -0.2794 0.9906)
			)
			(stroke
				(width 0)
				(type default)
			)
			(fill no)
			(layer "F.CrtYd")
		)
		(fp_line
			(start -0.2794 -0.1016)
			(end -0.2794 0.9906)
			(stroke
				(width 0.1)
				(type default)
			)
			(layer "F.Fab")
		)
		(fp_line
			(start -0.2794 0.9906)
			(end 0.2794 0.9906)
			(stroke
				(width 0.1)
				(type default)
			)
			(layer "F.Fab")
		)
		(fp_line
			(start 0.2794 -0.1016)
			(end -0.2794 -0.1016)
			(stroke
				(width 0.1)
				(type default)
			)
			(layer "F.Fab")
		)
		(fp_line
			(start 0.2794 0.9906)
			(end 0.2794 -0.1016)
			(stroke
				(width 0.1)
				(type default)
			)
			(layer "F.Fab")
		)
		(pad "1" smd rect
			(at 0 0)
			(size 0.508 0.508)
			(layers "F.Cu" "F.Mask" "F.Paste")
			(net "SMB_VR_STBY_LVC3_SCL_R")
		)
		(pad "2" smd rect
			(at 0 0.889)
			(size 0.508 0.508)
			(layers "F.Cu" "F.Mask" "F.Paste")
			(net "SMB_VR_STBY_LVC3_SCL")
		)
		(zone
			(layer "F.Cu")
			(hatch none 0.5)
			(connect_pads
				(clearance 0)
			)
			(min_thickness 0.25)
			(keepout
				(tracks allowed)
				(vias not_allowed)
				(pads allowed)
				(copperpour not_allowed)
				(footprints allowed)
			)
			(placement
				(enabled no)
				(sheetname "")
			)
			(fill
				(thermal_gap 0.5)
				(thermal_bridge_width 0.5)
				(island_removal_mode 0)
			)
			(polygon
				(pts
					(xy 417.2966 -18.4912) (xy 417.8046 -18.4912) (xy 417.8046 -18.1102) (xy 417.2966 -18.1102)
				)
			)
		)
		(zone
			(layer "F.Cu")
			(hatch none 0.5)
			(connect_pads
				(clearance 0)
			)
			(min_thickness 0.25)
			(keepout
				(tracks not_allowed)
				(vias allowed)
				(pads allowed)
				(copperpour not_allowed)
				(footprints allowed)
			)
			(placement
				(enabled no)
				(sheetname "")
			)
			(fill
				(thermal_gap 0.5)
				(thermal_bridge_width 0.5)
				(island_removal_mode 0)
			)
			(polygon
				(pts
					(xy 417.2966 -18.1102) (xy 417.8046 -18.1102) (xy 417.8046 -18.4912) (xy 417.2966 -18.4912)
				)
			)
		)
	)
)
